(kicad_pcb
	(version 20241229)
	(generator "pcbnew")
	(generator_version "9.0")
	(general
		(thickness 1.63)
		(legacy_teardrops no)
	)
	(paper "A4")
	(title_block
		(title "CM4 Baseboard")
		(date "2026-01-05")
		(rev "1.1.1")
		(company "Antmicro Ltd")
		(comment 1 "www.antmicro.com")
		(comment 9 "footprints 275-278 of 506")
	)
	(layers
		(0 "F.Cu" signal)
		(4 "In1.Cu" power)
		(6 "In2.Cu" power)
		(8 "In3.Cu" signal)
		(10 "In4.Cu" signal)
		(2 "B.Cu" signal)
		(9 "F.Adhes" user "F.Adhesive")
		(11 "B.Adhes" user "B.Adhesive")
		(13 "F.Paste" user)
		(15 "B.Paste" user)
		(5 "F.SilkS" user "F.Silkscreen")
		(7 "B.SilkS" user "B.Silkscreen")
		(1 "F.Mask" user)
		(3 "B.Mask" user)
		(17 "Dwgs.User" user "User.Drawings")
		(19 "Cmts.User" user "User.Comments")
		(21 "Eco1.User" user "User.Eco1")
		(23 "Eco2.User" user "User.Eco2")
		(25 "Edge.Cuts" user)
		(27 "Margin" user)
		(31 "F.CrtYd" user "F.Courtyard")
		(29 "B.CrtYd" user "B.Courtyard")
		(35 "F.Fab" user)
		(33 "B.Fab" user)
	)
	(footprint "antmicro-footprints:C_0402_1005Metric"
		(layer "F.Cu")
		(at 86.467962 148.2165)
		(descr "Capacitor SMD 0402")
		(tags "capacitor SMD 0402")
		(property "Reference" "C936"
			(at -0.667962 1.6085 0)
			(layer "F.SilkS")
			(effects
				(font
					(size 0.7 0.7)
					(thickness 0.15)
				)
				(justify right bottom)
			)
		)
		(property "Value" "C_100n_0402"
			(at -1.022927 2.155213 0)
			(layer "F.Fab")
			(effects
				(font
					(size 0.7 0.7)
					(thickness 0.15)
				)
				(justify left bottom)
			)
		)
		(property "Datasheet" "https://www.murata.com/products/productdetail?partno=GRM155R61H104KE14%23"
			(at 0 0 0)
			(layer "F.Fab")
			(hide yes)
			(effects
				(font
					(size 1.27 1.27)
					(thickness 0.15)
				)
			)
		)
		(property "MPN" "GRM155R61H104KE14D"
			(at 0 0 0)
			(unlocked yes)
			(layer "F.Fab")
			(hide yes)
			(effects
				(font
					(size 1 1)
					(thickness 0.15)
				)
			)
		)
		(property "Manufacturer" "Murata"
			(at 0 0 0)
			(unlocked yes)
			(layer "F.Fab")
			(hide yes)
			(effects
				(font
					(size 1 1)
					(thickness 0.15)
				)
			)
		)
		(property "License" "Apache-2.0"
			(at 0 0 0)
			(unlocked yes)
			(layer "F.Fab")
			(hide yes)
			(effects
				(font
					(size 1 1)
					(thickness 0.15)
				)
			)
		)
		(property "Author" "Antmicro"
			(at 0 0 0)
			(unlocked yes)
			(layer "F.Fab")
			(hide yes)
			(effects
				(font
					(size 1 1)
					(thickness 0.15)
				)
			)
		)
		(property "Val" "100n"
			(at 0 0 0)
			(unlocked yes)
			(layer "F.Fab")
			(hide yes)
			(effects
				(font
					(size 1 1)
					(thickness 0.15)
				)
			)
		)
		(property "Voltage" "50V"
			(at 0 0 0)
			(unlocked yes)
			(layer "F.Fab")
			(hide yes)
			(effects
				(font
					(size 1 1)
					(thickness 0.15)
				)
			)
		)
		(property "Dielectric" "X5R"
			(at 0 0 0)
			(unlocked yes)
			(layer "F.Fab")
			(hide yes)
			(effects
				(font
					(size 1 1)
					(thickness 0.15)
				)
			)
		)
		(sheetname "/USB/")
		(sheetfile "usb.kicad_sch")
		(attr smd)
		(fp_rect
			(start -0.925 -0.47)
			(end 0.925 0.47)
			(stroke
				(width 0.05)
				(type default)
			)
			(fill no)
			(layer "F.CrtYd")
		)
		(fp_line
			(start -0.494 -0.25)
			(end 0.504 -0.25)
			(stroke
				(width 0.15)
				(type solid)
			)
			(layer "F.Fab")
		)
		(fp_line
			(start -0.494 0.248)
			(end -0.494 -0.25)
			(stroke
				(width 0.15)
				(type solid)
			)
			(layer "F.Fab")
		)
		(fp_line
			(start 0.504 -0.25)
			(end 0.504 0.248)
			(stroke
				(width 0.15)
				(type solid)
			)
			(layer "F.Fab")
		)
		(fp_line
			(start 0.504 0.248)
			(end -0.494 0.248)
			(stroke
				(width 0.15)
				(type solid)
			)
			(layer "F.Fab")
		)
		(fp_text user "License: Apache-2.0"
			(at -0.939 5.799 0)
			(layer "F.Fab")
			(effects
				(font
					(size 0.7 0.7)
					(thickness 0.15)
				)
				(justify left bottom)
			)
		)
		(fp_text user "${REFERENCE}"
			(at -0.939 4.599 0)
			(layer "F.Fab")
			(effects
				(font
					(size 0.7 0.7)
					(thickness 0.15)
				)
				(justify left bottom)
			)
		)
		(fp_text user "Author: Antmicro"
			(at -0.939 3.399 0)
			(layer "F.Fab")
			(effects
				(font
					(size 0.7 0.7)
					(thickness 0.15)
				)
				(justify left bottom)
			)
		)
		(pad "1" smd roundrect
			(at -0.48 0)
			(size 0.59 0.64)
			(layers "F.Cu" "F.Mask" "F.Paste")
			(roundrect_rratio 0.25)
			(net 3 "GND")
			(pintype "passive")
		)
		(pad "2" smd roundrect
			(at 0.48 0)
			(size 0.59 0.64)
			(layers "F.Cu" "F.Mask" "F.Paste")
			(roundrect_rratio 0.25)
			(net 9 "+3V3")
			(pintype "passive")
		)
	)
	(footprint "antmicro-footprints:C_0402_1005Metric"
		(layer "F.Cu")
		(at 139.017962 163.4165 180)
		(descr "Capacitor SMD 0402")
		(tags "capacitor SMD 0402")
		(property "Reference" "C507"
			(at -1.05 -2.57 0)
			(layer "F.SilkS")
			(effects
				(font
					(size 0.7 0.7)
					(thickness 0.15)
				)
				(justify right bottom)
			)
		)
		(property "Value" "C_1u_0402"
			(at -1.022927 2.155213 0)
			(layer "F.Fab")
			(effects
				(font
					(size 0.7 0.7)
					(thickness 0.15)
				)
				(justify right bottom)
			)
		)
		(property "Datasheet" "https://product.tdk.com/en/search/capacitor/ceramic/mlcc/info?part_no=C1005X6S1A105K050BC"
			(at 0 0 180)
			(layer "F.Fab")
			(hide yes)
			(effects
				(font
					(size 1.27 1.27)
					(thickness 0.15)
				)
			)
		)
		(property "Manufacturer" "TDK"
			(at 0 0 180)
			(unlocked yes)
			(layer "F.Fab")
			(hide yes)
			(effects
				(font
					(size 1 1)
					(thickness 0.15)
				)
			)
		)
		(property "MPN" "C1005X6S1A105K050BC"
			(at 0 0 180)
			(unlocked yes)
			(layer "F.Fab")
			(hide yes)
			(effects
				(font
					(size 1 1)
					(thickness 0.15)
				)
			)
		)
		(property "Val" "1u"
			(at 0 0 180)
			(unlocked yes)
			(layer "F.Fab")
			(hide yes)
			(effects
				(font
					(size 1 1)
					(thickness 0.15)
				)
			)
		)
		(property "License" "Apache-2.0"
			(at 0 0 180)
			(unlocked yes)
			(layer "F.Fab")
			(hide yes)
			(effects
				(font
					(size 1 1)
					(thickness 0.15)
				)
			)
		)
		(property "Author" "Antmicro"
			(at 0 0 180)
			(unlocked yes)
			(layer "F.Fab")
			(hide yes)
			(effects
				(font
					(size 1 1)
					(thickness 0.15)
				)
			)
		)
		(property "Voltage" ""
			(at 0 0 180)
			(unlocked yes)
			(layer "F.Fab")
			(hide yes)
			(effects
				(font
					(size 1 1)
					(thickness 0.15)
				)
			)
		)
		(property "Dielectric" ""
			(at 0 0 180)
			(unlocked yes)
			(layer "F.Fab")
			(hide yes)
			(effects
				(font
					(size 1 1)
					(thickness 0.15)
				)
			)
		)
		(sheetname "/NVMe & microSD/")
		(sheetfile "nvme-micro-sd.kicad_sch")
		(attr smd)
		(fp_rect
			(start -0.925 -0.47)
			(end 0.925 0.47)
			(stroke
				(width 0.05)
				(type default)
			)
			(fill no)
			(layer "F.CrtYd")
		)
		(fp_line
			(start 0.504 0.248)
			(end -0.494 0.248)
			(stroke
				(width 0.15)
				(type solid)
			)
			(layer "F.Fab")
		)
		(fp_line
			(start 0.504 -0.25)
			(end 0.504 0.248)
			(stroke
				(width 0.15)
				(type solid)
			)
			(layer "F.Fab")
		)
		(fp_line
			(start -0.494 0.248)
			(end -0.494 -0.25)
			(stroke
				(width 0.15)
				(type solid)
			)
			(layer "F.Fab")
		)
		(fp_line
			(start -0.494 -0.25)
			(end 0.504 -0.25)
			(stroke
				(width 0.15)
				(type solid)
			)
			(layer "F.Fab")
		)
		(fp_text user "License: Apache-2.0"
			(at -0.939 5.799 180)
			(layer "F.Fab")
			(effects
				(font
					(size 0.7 0.7)
					(thickness 0.15)
				)
				(justify left bottom)
			)
		)
		(fp_text user "${REFERENCE}"
			(at -0.939 4.599 180)
			(layer "F.Fab")
			(effects
				(font
					(size 0.7 0.7)
					(thickness 0.15)
				)
				(justify left bottom)
			)
		)
		(fp_text user "Author: Antmicro"
			(at -0.939 3.399 180)
			(layer "F.Fab")
			(effects
				(font
					(size 0.7 0.7)
					(thickness 0.15)
				)
				(justify left bottom)
			)
		)
		(pad "1" smd roundrect
			(at -0.48 0 180)
			(size 0.59 0.64)
			(layers "F.Cu" "F.Mask" "F.Paste")
			(roundrect_rratio 0.25)
			(net 3 "GND")
			(pintype "passive")
		)
		(pad "2" smd roundrect
			(at 0.48 0 180)
			(size 0.59 0.64)
			(layers "F.Cu" "F.Mask" "F.Paste")
			(roundrect_rratio 0.25)
			(net 9 "+3V3")
			(pintype "passive")
		)
	)
	(footprint "antmicro-footprints:FB_0402_1005Metric"
		(layer "F.Cu")
		(at 92.142962 146.2415 90)
		(descr "Ferrite Bead SMD 0402")
		(tags "ferrite bead SMD 0402")
		(property "Reference" "FB901"
			(at -3.23 1.175 90)
			(layer "F.SilkS")
			(effects
				(font
					(size 0.7 0.7)
					(thickness 0.15)
				)
				(justify left bottom)
			)
		)
		(property "Value" "FB_120Z_1.3A_Murata-BLM15PD_0402"
			(at 0 1.4 90)
			(layer "F.Fab")
			(effects
				(font
					(size 0.7 0.7)
					(thickness 0.15)
				)
				(justify left bottom)
			)
		)
		(property "Datasheet" "https://www.murata.com/en-us/products/productdata/8796740059166/ENFA0018.pdf"
			(at 0 0 90)
			(layer "F.Fab")
			(hide yes)
			(effects
				(font
					(size 1.27 1.27)
					(thickness 0.15)
				)
			)
		)
		(property "MPN" "BLM15PD121SN1D"
			(at 0 0 90)
			(unlocked yes)
			(layer "F.Fab")
			(hide yes)
			(effects
				(font
					(size 1 1)
					(thickness 0.15)
				)
			)
		)
		(property "Manufacturer" "Murata"
			(at 0 0 90)
			(unlocked yes)
			(layer "F.Fab")
			(hide yes)
			(effects
				(font
					(size 1 1)
					(thickness 0.15)
				)
			)
		)
		(property "Author" "Antmicro"
			(at 0 0 90)
			(unlocked yes)
			(layer "F.Fab")
			(hide yes)
			(effects
				(font
					(size 1 1)
					(thickness 0.15)
				)
			)
		)
		(property "License" "Apache-2.0"
			(at 0 0 90)
			(unlocked yes)
			(layer "F.Fab")
			(hide yes)
			(effects
				(font
					(size 1 1)
					(thickness 0.15)
				)
			)
		)
		(property "Val" "120Z/1.3A"
			(at 0 0 90)
			(unlocked yes)
			(layer "F.Fab")
			(hide yes)
			(effects
				(font
					(size 1 1)
					(thickness 0.15)
				)
			)
		)
		(property "Current" ""
			(at 0 0 90)
			(unlocked yes)
			(layer "F.Fab")
			(hide yes)
			(effects
				(font
					(size 1 1)
					(thickness 0.15)
				)
			)
		)
		(sheetname "/USB/")
		(sheetfile "usb.kicad_sch")
		(attr smd)
		(fp_rect
			(start -0.925 -0.47)
			(end 0.925 0.47)
			(stroke
				(width 0.05)
				(type default)
			)
			(fill no)
			(layer "F.CrtYd")
		)
		(fp_rect
			(start -0.5 -0.25)
			(end 0.5 0.25)
			(stroke
				(width 0.15)
				(type solid)
			)
			(fill no)
			(layer "F.Fab")
		)
		(fp_text user "${REFERENCE}"
			(at -0.95 3.168 90)
			(layer "F.Fab")
			(effects
				(font
					(size 0.7 0.7)
					(thickness 0.15)
				)
				(justify left bottom)
			)
		)
		(fp_text user "License: Apache-2.0"
			(at -0.95 5.169 90)
			(layer "F.Fab")
			(effects
				(font
					(size 0.7 0.7)
					(thickness 0.15)
				)
				(justify left bottom)
			)
		)
		(fp_text user "Author: Antmicro"
			(at -0.95 4.169 90)
			(layer "F.Fab")
			(effects
				(font
					(size 0.7 0.7)
					(thickness 0.15)
				)
				(justify left bottom)
			)
		)
		(pad "1" smd roundrect
			(at -0.48 0 90)
			(size 0.59 0.64)
			(layers "F.Cu" "F.Mask" "F.Paste")
			(roundrect_rratio 0.25)
			(net 27 "/USB/USB_3V3")
			(pintype "passive")
		)
		(pad "2" smd roundrect
			(at 0.48 0 90)
			(size 0.59 0.64)
			(layers "F.Cu" "F.Mask" "F.Paste")
			(roundrect_rratio 0.25)
			(net 31 "/USB/VREGIN")
			(pintype "passive")
		)
	)
	(footprint "antmicro-footprints:C_0402_1005Metric"
		(layer "F.Cu")
		(at 62.117962 177.6915 -90)
		(descr "Capacitor SMD 0402")
		(tags "capacitor SMD 0402")
		(property "Reference" "C824"
			(at -2.805 14.88 90)
			(layer "F.SilkS")
			(effects
				(font
					(size 0.7 0.7)
					(thickness 0.15)
				)
				(justify right bottom)
			)
		)
		(property "Value" "C_39p_0402"
			(at -1.022927 2.155213 90)
			(layer "F.Fab")
			(effects
				(font
					(size 0.7 0.7)
					(thickness 0.15)
				)
				(justify right bottom)
			)
		)
		(property "Datasheet" "https://spicat.kyocera-avx.com/product/mlcc/chartview/04025A390JAT2A/"
			(at 0 0 270)
			(layer "F.Fab")
			(hide yes)
			(effects
				(font
					(size 1.27 1.27)
					(thickness 0.15)
				)
			)
		)
		(property "Description" "SMD Multilayer Ceramic Capacitor, 39 pF, 50 V, 0402 [1005 Metric], ± 5%, C0G / NP0, AVX 0402 MLCC"
			(at 0 0 270)
			(layer "F.Fab")
			(hide yes)
			(effects
				(font
					(size 1.27 1.27)
					(thickness 0.15)
				)
			)
		)
		(property "MPN" "04025A390JAT2A"
			(at 0 0 270)
			(unlocked yes)
			(layer "F.Fab")
			(hide yes)
			(effects
				(font
					(size 1 1)
					(thickness 0.15)
				)
			)
		)
		(property "Manufacturer" "KYOCERA AVX"
			(at 0 0 270)
			(unlocked yes)
			(layer "F.Fab")
			(hide yes)
			(effects
				(font
					(size 1 1)
					(thickness 0.15)
				)
			)
		)
		(property "License" "Apache-2.0"
			(at 0 0 270)
			(unlocked yes)
			(layer "F.Fab")
			(hide yes)
			(effects
				(font
					(size 1 1)
					(thickness 0.15)
				)
			)
		)
		(property "Author" "Antmicro"
			(at 0 0 270)
			(unlocked yes)
			(layer "F.Fab")
			(hide yes)
			(effects
				(font
					(size 1 1)
					(thickness 0.15)
				)
			)
		)
		(property "Val" "39p"
			(at 0 0 270)
			(unlocked yes)
			(layer "F.Fab")
			(hide yes)
			(effects
				(font
					(size 1 1)
					(thickness 0.15)
				)
			)
		)
		(property "Voltage" ""
			(at 0 0 270)
			(unlocked yes)
			(layer "F.Fab")
			(hide yes)
			(effects
				(font
					(size 1 1)
					(thickness 0.15)
				)
			)
		)
		(property "Dielectric" ""
			(at 0 0 270)
			(unlocked yes)
			(layer "F.Fab")
			(hide yes)
			(effects
				(font
					(size 1 1)
					(thickness 0.15)
				)
			)
		)
		(sheetname "/Peripherals/")
		(sheetfile "peripherals.kicad_sch")
		(attr smd)
		(fp_rect
			(start -0.925 -0.47)
			(end 0.925 0.47)
			(stroke
				(width 0.05)
				(type default)
			)
			(fill no)
			(layer "F.CrtYd")
		)
		(fp_line
			(start -0.494 0.248)
			(end -0.494 -0.25)
			(stroke
				(width 0.15)
				(type solid)
			)
			(layer "F.Fab")
		)
		(fp_line
			(start 0.504 0.248)
			(end -0.494 0.248)
			(stroke
				(width 0.15)
				(type solid)
			)
			(layer "F.Fab")
		)
		(fp_line
			(start -0.494 -0.25)
			(end 0.504 -0.25)
			(stroke
				(width 0.15)
				(type solid)
			)
			(layer "F.Fab")
		)
		(fp_line
			(start 0.504 -0.25)
			(end 0.504 0.248)
			(stroke
				(width 0.15)
				(type solid)
			)
			(layer "F.Fab")
		)
		(fp_text user "${REFERENCE}"
			(at -0.939 4.599 270)
			(layer "F.Fab")
			(effects
				(font
					(size 0.7 0.7)
					(thickness 0.15)
				)
				(justify left bottom)
			)
		)
		(fp_text user "Author: Antmicro"
			(at -0.939 3.399 270)
			(layer "F.Fab")
			(effects
				(font
					(size 0.7 0.7)
					(thickness 0.15)
				)
				(justify left bottom)
			)
		)
		(fp_text user "License: Apache-2.0"
			(at -0.939 5.799 270)
			(layer "F.Fab")
			(effects
				(font
					(size 0.7 0.7)
					(thickness 0.15)
				)
				(justify left bottom)
			)
		)
		(pad "1" smd roundrect
			(at -0.48 0 270)
			(size 0.59 0.64)
			(layers "F.Cu" "F.Mask" "F.Paste")
			(roundrect_rratio 0.25)
			(net 3 "GND")
			(pintype "passive")
		)
		(pad "2" smd roundrect
			(at 0.48 0 270)
			(size 0.59 0.64)
			(layers "F.Cu" "F.Mask" "F.Paste")
			(roundrect_rratio 0.25)
			(net 100 "Net-(C811-Pad2)")
			(pintype "passive")
		)
	)
)
